(kicad_pcb
	(version 20260206)
	(generator "pcbnew")
	(generator_version "10.0")
	(general
		(thickness 1.6)
		(legacy_teardrops no)
	)
	(paper "A4")
	(title_block
		(title "04192023_DAF0TMB3IC0_F0TG_MB_C_brd_V02_OCP.brd")
		(comment 1 "Grand Teton / footprints 4032-4038 of 8354")
	)
	(layers
		(0 "F.Cu" signal "TOP")
		(4 "In1.Cu" signal "GND")
		(6 "In2.Cu" signal "IN1")
		(8 "In3.Cu" signal "GND1")
		(10 "In4.Cu" signal "IN2")
		(12 "In5.Cu" signal "GND2")
		(14 "In6.Cu" signal "IN3")
		(16 "In7.Cu" signal "GND3")
		(18 "In8.Cu" signal "VCC")
		(20 "In9.Cu" signal "VCC1")
		(22 "In10.Cu" signal "GND4")
		(24 "In11.Cu" signal "IN4")
		(26 "In12.Cu" signal "GND5")
		(28 "In13.Cu" signal "IN5")
		(30 "In14.Cu" signal "GND6")
		(32 "In15.Cu" signal "IN6")
		(34 "In16.Cu" signal "GND7")
		(2 "B.Cu" signal "BOTTOM")
		(9 "F.Adhes" user "F.Adhesive")
		(11 "B.Adhes" user "B.Adhesive")
		(13 "F.Paste" user "Package Geometry/Pastemask Top")
		(15 "B.Paste" user "Package Geometry/Pastemask Bottom")
		(5 "F.SilkS" user "Ref Des/Silkscreen Top")
		(7 "B.SilkS" user "Ref Des/Silkscreen Bottom")
		(1 "F.Mask" user "Board Geometry/Soldermask Top")
		(3 "B.Mask" user "Board Geometry/Soldermask Bottom")
		(17 "Dwgs.User" user "User.Drawings")
		(19 "Cmts.User" user "User.Comments")
		(21 "Eco1.User" user "User.Eco1")
		(23 "Eco2.User" user "User.Eco2")
		(25 "Edge.Cuts" user "Board Geometry/Outline")
		(27 "Margin" user)
		(31 "F.CrtYd" user "Package Geometry/Place Bound Top")
		(29 "B.CrtYd" user "Package Geometry/Place Bound Bottom")
		(35 "F.Fab" user "Ref Des/Assembly Top")
		(33 "B.Fab" user "Ref Des/Assembly Bottom")
	)
	(footprint ""
		(layer "F.Cu")
		(at 255.831086 -380.66853)
		(property "Reference" "PR2528"
			(at 0 0 0)
			(layer "F.SilkS")
			(hide yes)
			(effects
				(font
					(size 1.27 1.27)
				)
			)
		)
		(property "Value" ""
			(at 0 0 0)
			(layer "F.Fab")
			(effects
				(font
					(size 1.27 1.27)
				)
			)
		)
		(duplicate_pad_numbers_are_jumpers no)
		(fp_line
			(start -0.7874 -0.4064)
			(end 0.7874 -0.4064)
			(stroke
				(width 0.1524)
				(type default)
			)
			(layer "F.SilkS")
		)
		(fp_line
			(start -0.7874 0.4064)
			(end -0.7874 -0.4064)
			(stroke
				(width 0.1524)
				(type default)
			)
			(layer "F.SilkS")
		)
		(fp_line
			(start 0.7874 -0.4064)
			(end 0.7874 0.4064)
			(stroke
				(width 0.1524)
				(type default)
			)
			(layer "F.SilkS")
		)
		(fp_line
			(start 0.7874 0.4064)
			(end -0.7874 0.4064)
			(stroke
				(width 0.1524)
				(type default)
			)
			(layer "F.SilkS")
		)
		(fp_line
			(start -0.67945 -0.305054)
			(end -0.12065 -0.305054)
			(stroke
				(width 0.1)
				(type default)
			)
			(layer "F.Fab")
		)
		(fp_line
			(start -0.67945 0.3048)
			(end -0.67945 -0.305054)
			(stroke
				(width 0.1)
				(type default)
			)
			(layer "F.Fab")
		)
		(fp_line
			(start -0.12065 -0.305054)
			(end -0.12065 -0.2794)
			(stroke
				(width 0.1)
				(type default)
			)
			(layer "F.Fab")
		)
		(fp_line
			(start -0.12065 -0.2794)
			(end 0.12065 -0.2794)
			(stroke
				(width 0.1)
				(type default)
			)
			(layer "F.Fab")
		)
		(fp_line
			(start -0.12065 0.2794)
			(end -0.12065 0.3048)
			(stroke
				(width 0.1)
				(type default)
			)
			(layer "F.Fab")
		)
		(fp_line
			(start -0.12065 0.3048)
			(end -0.67945 0.3048)
			(stroke
				(width 0.1)
				(type default)
			)
			(layer "F.Fab")
		)
		(fp_line
			(start 0.120396 0.2794)
			(end -0.12065 0.2794)
			(stroke
				(width 0.1)
				(type default)
			)
			(layer "F.Fab")
		)
		(fp_line
			(start 0.120396 0.3048)
			(end 0.120396 0.2794)
			(stroke
				(width 0.1)
				(type default)
			)
			(layer "F.Fab")
		)
		(fp_line
			(start 0.12065 -0.3048)
			(end 0.67945 -0.3048)
			(stroke
				(width 0.1)
				(type default)
			)
			(layer "F.Fab")
		)
		(fp_line
			(start 0.12065 -0.2794)
			(end 0.12065 -0.3048)
			(stroke
				(width 0.1)
				(type default)
			)
			(layer "F.Fab")
		)
		(fp_line
			(start 0.67945 -0.3048)
			(end 0.67945 0.3048)
			(stroke
				(width 0.1)
				(type default)
			)
			(layer "F.Fab")
		)
		(fp_line
			(start 0.67945 0.3048)
			(end 0.120396 0.3048)
			(stroke
				(width 0.1)
				(type default)
			)
			(layer "F.Fab")
		)
		(pad "1" smd circle
			(at -0.40005 0)
			(size 0 0)
			(layers "F.Cu" "F.Mask" "F.Paste")
			(net "P12V_HSC_GATE_G1")
		)
		(pad "2" smd circle
			(at 0.40005 0)
			(size 0 0)
			(layers "F.Cu" "F.Mask" "F.Paste")
			(net "P12V_HSC_GATE2")
		)
	)
	(footprint ""
		(layer "F.Cu")
		(at 425.896532 -358.570276 180)
		(property "Reference" "PC219_1"
			(at 0 0 180)
			(layer "F.SilkS")
			(hide yes)
			(effects
				(font
					(size 1.27 1.27)
				)
			)
		)
		(property "Value" ""
			(at 0 0 180)
			(layer "F.Fab")
			(effects
				(font
					(size 1.27 1.27)
				)
			)
		)
		(duplicate_pad_numbers_are_jumpers no)
		(fp_line
			(start 1.524 0.762)
			(end -1.524 0.762)
			(stroke
				(width 0.1524)
				(type default)
			)
			(layer "F.SilkS")
		)
		(fp_line
			(start 1.524 -0.762)
			(end 1.524 0.762)
			(stroke
				(width 0.1524)
				(type default)
			)
			(layer "F.SilkS")
		)
		(fp_line
			(start -1.524 0.762)
			(end -1.524 -0.762)
			(stroke
				(width 0.1524)
				(type default)
			)
			(layer "F.SilkS")
		)
		(fp_line
			(start -1.524 -0.762)
			(end 1.524 -0.762)
			(stroke
				(width 0.1524)
				(type default)
			)
			(layer "F.SilkS")
		)
		(fp_line
			(start 1.1049 0.724916)
			(end 1.1049 -0.724916)
			(stroke
				(width 0.1)
				(type default)
			)
			(layer "F.Fab")
		)
		(fp_line
			(start 1.1049 -0.724916)
			(end -1.1049 -0.724916)
			(stroke
				(width 0.1)
				(type default)
			)
			(layer "F.Fab")
		)
		(fp_line
			(start -1.1049 0.724916)
			(end 1.1049 0.724916)
			(stroke
				(width 0.1)
				(type default)
			)
			(layer "F.Fab")
		)
		(fp_line
			(start -1.1049 -0.724916)
			(end -1.1049 0.724916)
			(stroke
				(width 0.1)
				(type default)
			)
			(layer "F.Fab")
		)
		(pad "1" smd rect
			(at -0.889 0)
			(size 1.016 1.27)
			(layers "F.Cu" "F.Mask" "F.Paste")
			(net "SW_P12V_AUX_PVDD11_S3_P0_FLT")
		)
		(pad "2" smd rect
			(at 0.889 0)
			(size 1.016 1.27)
			(layers "F.Cu" "F.Mask" "F.Paste")
			(net "GND")
		)
	)
	(footprint ""
		(layer "F.Cu")
		(at 125.992636 -61.767212 180)
		(property "Reference" "R1743"
			(at 0 0 180)
			(layer "F.SilkS")
			(hide yes)
			(effects
				(font
					(size 1.27 1.27)
				)
			)
		)
		(property "Value" ""
			(at 0 0 180)
			(layer "F.Fab")
			(effects
				(font
					(size 1.27 1.27)
				)
			)
		)
		(duplicate_pad_numbers_are_jumpers no)
		(fp_line
			(start 0.7874 0.4064)
			(end -0.7874 0.4064)
			(stroke
				(width 0.1524)
				(type default)
			)
			(layer "F.SilkS")
		)
		(fp_line
			(start 0.7874 -0.4064)
			(end 0.7874 0.4064)
			(stroke
				(width 0.1524)
				(type default)
			)
			(layer "F.SilkS")
		)
		(fp_line
			(start -0.7874 0.4064)
			(end -0.7874 -0.4064)
			(stroke
				(width 0.1524)
				(type default)
			)
			(layer "F.SilkS")
		)
		(fp_line
			(start -0.7874 -0.4064)
			(end 0.7874 -0.4064)
			(stroke
				(width 0.1524)
				(type default)
			)
			(layer "F.SilkS")
		)
		(fp_line
			(start 0.67945 0.3048)
			(end 0.120396 0.3048)
			(stroke
				(width 0.1)
				(type default)
			)
			(layer "F.Fab")
		)
		(fp_line
			(start 0.67945 -0.3048)
			(end 0.67945 0.3048)
			(stroke
				(width 0.1)
				(type default)
			)
			(layer "F.Fab")
		)
		(fp_line
			(start 0.12065 -0.2794)
			(end 0.12065 -0.3048)
			(stroke
				(width 0.1)
				(type default)
			)
			(layer "F.Fab")
		)
		(fp_line
			(start 0.12065 -0.3048)
			(end 0.67945 -0.3048)
			(stroke
				(width 0.1)
				(type default)
			)
			(layer "F.Fab")
		)
		(fp_line
			(start 0.120396 0.3048)
			(end 0.120396 0.2794)
			(stroke
				(width 0.1)
				(type default)
			)
			(layer "F.Fab")
		)
		(fp_line
			(start 0.120396 0.2794)
			(end -0.12065 0.2794)
			(stroke
				(width 0.1)
				(type default)
			)
			(layer "F.Fab")
		)
		(fp_line
			(start -0.12065 0.3048)
			(end -0.67945 0.3048)
			(stroke
				(width 0.1)
				(type default)
			)
			(layer "F.Fab")
		)
		(fp_line
			(start -0.12065 0.2794)
			(end -0.12065 0.3048)
			(stroke
				(width 0.1)
				(type default)
			)
			(layer "F.Fab")
		)
		(fp_line
			(start -0.12065 -0.2794)
			(end 0.12065 -0.2794)
			(stroke
				(width 0.1)
				(type default)
			)
			(layer "F.Fab")
		)
		(fp_line
			(start -0.12065 -0.305054)
			(end -0.12065 -0.2794)
			(stroke
				(width 0.1)
				(type default)
			)
			(layer "F.Fab")
		)
		(fp_line
			(start -0.67945 0.3048)
			(end -0.67945 -0.305054)
			(stroke
				(width 0.1)
				(type default)
			)
			(layer "F.Fab")
		)
		(fp_line
			(start -0.67945 -0.305054)
			(end -0.12065 -0.305054)
			(stroke
				(width 0.1)
				(type default)
			)
			(layer "F.Fab")
		)
		(pad "1" smd circle
			(at -0.40005 0 180)
			(size 0 0)
			(layers "F.Cu" "F.Mask" "F.Paste")
			(net "JTAG_SCM_PLD_R_TDO")
		)
		(pad "2" smd circle
			(at 0.40005 0 180)
			(size 0 0)
			(layers "F.Cu" "F.Mask" "F.Paste")
			(net "JTAG_SCM_PLD_TDO")
		)
	)
	(footprint ""
		(layer "F.Cu")
		(at 328.288142 -390.652)
		(property "Reference" "R969"
			(at 0 0 0)
			(layer "F.SilkS")
			(hide yes)
			(effects
				(font
					(size 1.27 1.27)
				)
			)
		)
		(property "Value" ""
			(at 0 0 0)
			(layer "F.Fab")
			(effects
				(font
					(size 1.27 1.27)
				)
			)
		)
		(duplicate_pad_numbers_are_jumpers no)
		(fp_line
			(start -0.32512 -0.175006)
			(end 0.32512 -0.175006)
			(stroke
				(width 0.1)
				(type default)
			)
			(layer "F.Fab")
		)
		(fp_line
			(start -0.32512 0.175006)
			(end -0.32512 -0.175006)
			(stroke
				(width 0.1)
				(type default)
			)
			(layer "F.Fab")
		)
		(fp_line
			(start 0.32512 -0.175006)
			(end 0.32512 0.175006)
			(stroke
				(width 0.1)
				(type default)
			)
			(layer "F.Fab")
		)
		(fp_line
			(start 0.32512 0.175006)
			(end -0.32512 0.175006)
			(stroke
				(width 0.1)
				(type default)
			)
			(layer "F.Fab")
		)
		(pad "1" smd rect
			(at -0.2667 0)
			(size 0.3048 0.381)
			(layers "F.Cu" "F.Mask" "F.Paste")
			(net "RT_CPU0_P0_ADDR1")
		)
		(pad "2" smd rect
			(at 0.2667 0 180)
			(size 0.3048 0.381)
			(layers "F.Cu" "F.Mask" "F.Paste")
			(net "GND")
		)
	)
	(footprint ""
		(layer "F.Cu")
		(at 62.63386 -351.372932 90)
		(property "Reference" "PR266"
			(at 0 0 90)
			(layer "F.SilkS")
			(hide yes)
			(effects
				(font
					(size 1.27 1.27)
				)
			)
		)
		(property "Value" ""
			(at 0 0 90)
			(layer "F.Fab")
			(effects
				(font
					(size 1.27 1.27)
				)
			)
		)
		(duplicate_pad_numbers_are_jumpers no)
		(fp_line
			(start 0.7874 -0.4064)
			(end 0.7874 0.4064)
			(stroke
				(width 0.1524)
				(type default)
			)
			(layer "F.SilkS")
		)
		(fp_line
			(start -0.7874 -0.4064)
			(end 0.7874 -0.4064)
			(stroke
				(width 0.1524)
				(type default)
			)
			(layer "F.SilkS")
		)
		(fp_line
			(start 0.7874 0.4064)
			(end -0.7874 0.4064)
			(stroke
				(width 0.1524)
				(type default)
			)
			(layer "F.SilkS")
		)
		(fp_line
			(start -0.7874 0.4064)
			(end -0.7874 -0.4064)
			(stroke
				(width 0.1524)
				(type default)
			)
			(layer "F.SilkS")
		)
		(fp_line
			(start -0.12065 -0.305054)
			(end -0.12065 -0.2794)
			(stroke
				(width 0.1)
				(type default)
			)
			(layer "F.Fab")
		)
		(fp_line
			(start -0.67945 -0.305054)
			(end -0.12065 -0.305054)
			(stroke
				(width 0.1)
				(type default)
			)
			(layer "F.Fab")
		)
		(fp_line
			(start 0.67945 -0.3048)
			(end 0.67945 0.3048)
			(stroke
				(width 0.1)
				(type default)
			)
			(layer "F.Fab")
		)
		(fp_line
			(start 0.12065 -0.3048)
			(end 0.67945 -0.3048)
			(stroke
				(width 0.1)
				(type default)
			)
			(layer "F.Fab")
		)
		(fp_line
			(start 0.12065 -0.2794)
			(end 0.12065 -0.3048)
			(stroke
				(width 0.1)
				(type default)
			)
			(layer "F.Fab")
		)
		(fp_line
			(start -0.12065 -0.2794)
			(end 0.12065 -0.2794)
			(stroke
				(width 0.1)
				(type default)
			)
			(layer "F.Fab")
		)
		(fp_line
			(start 0.120396 0.2794)
			(end -0.12065 0.2794)
			(stroke
				(width 0.1)
				(type default)
			)
			(layer "F.Fab")
		)
		(fp_line
			(start -0.12065 0.2794)
			(end -0.12065 0.3048)
			(stroke
				(width 0.1)
				(type default)
			)
			(layer "F.Fab")
		)
		(fp_line
			(start 0.67945 0.3048)
			(end 0.120396 0.3048)
			(stroke
				(width 0.1)
				(type default)
			)
			(layer "F.Fab")
		)
		(fp_line
			(start 0.120396 0.3048)
			(end 0.120396 0.2794)
			(stroke
				(width 0.1)
				(type default)
			)
			(layer "F.Fab")
		)
		(fp_line
			(start -0.12065 0.3048)
			(end -0.67945 0.3048)
			(stroke
				(width 0.1)
				(type default)
			)
			(layer "F.Fab")
		)
		(fp_line
			(start -0.67945 0.3048)
			(end -0.67945 -0.305054)
			(stroke
				(width 0.1)
				(type default)
			)
			(layer "F.Fab")
		)
		(pad "1" smd circle
			(at -0.40005 0 90)
			(size 0 0)
			(layers "F.Cu" "F.Mask" "F.Paste")
			(net "SW_PVDDCR_CPU1_P1_BOOT4")
		)
		(pad "2" smd circle
			(at 0.40005 0 90)
			(size 0 0)
			(layers "F.Cu" "F.Mask" "F.Paste")
			(net "SW_PVDDCR_CPU1_P1_BOOT4_R")
		)
	)
	(footprint ""
		(layer "F.Cu")
		(at 43.88231 -351.932748)
		(property "Reference" "PR274"
			(at 0 0 0)
			(layer "F.SilkS")
			(hide yes)
			(effects
				(font
					(size 1.27 1.27)
				)
			)
		)
		(property "Value" ""
			(at 0 0 0)
			(layer "F.Fab")
			(effects
				(font
					(size 1.27 1.27)
				)
			)
		)
		(duplicate_pad_numbers_are_jumpers no)
		(fp_line
			(start -0.7874 -0.4064)
			(end 0.7874 -0.4064)
			(stroke
				(width 0.1524)
				(type default)
			)
			(layer "F.SilkS")
		)
		(fp_line
			(start -0.7874 0.4064)
			(end -0.7874 -0.4064)
			(stroke
				(width 0.1524)
				(type default)
			)
			(layer "F.SilkS")
		)
		(fp_line
			(start 0.7874 -0.4064)
			(end 0.7874 0.4064)
			(stroke
				(width 0.1524)
				(type default)
			)
			(layer "F.SilkS")
		)
		(fp_line
			(start 0.7874 0.4064)
			(end -0.7874 0.4064)
			(stroke
				(width 0.1524)
				(type default)
			)
			(layer "F.SilkS")
		)
		(fp_line
			(start -0.67945 -0.305054)
			(end -0.12065 -0.305054)
			(stroke
				(width 0.1)
				(type default)
			)
			(layer "F.Fab")
		)
		(fp_line
			(start -0.67945 0.3048)
			(end -0.67945 -0.305054)
			(stroke
				(width 0.1)
				(type default)
			)
			(layer "F.Fab")
		)
		(fp_line
			(start -0.12065 -0.305054)
			(end -0.12065 -0.2794)
			(stroke
				(width 0.1)
				(type default)
			)
			(layer "F.Fab")
		)
		(fp_line
			(start -0.12065 -0.2794)
			(end 0.12065 -0.2794)
			(stroke
				(width 0.1)
				(type default)
			)
			(layer "F.Fab")
		)
		(fp_line
			(start -0.12065 0.2794)
			(end -0.12065 0.3048)
			(stroke
				(width 0.1)
				(type default)
			)
			(layer "F.Fab")
		)
		(fp_line
			(start -0.12065 0.3048)
			(end -0.67945 0.3048)
			(stroke
				(width 0.1)
				(type default)
			)
			(layer "F.Fab")
		)
		(fp_line
			(start 0.120396 0.2794)
			(end -0.12065 0.2794)
			(stroke
				(width 0.1)
				(type default)
			)
			(layer "F.Fab")
		)
		(fp_line
			(start 0.120396 0.3048)
			(end 0.120396 0.2794)
			(stroke
				(width 0.1)
				(type default)
			)
			(layer "F.Fab")
		)
		(fp_line
			(start 0.12065 -0.3048)
			(end 0.67945 -0.3048)
			(stroke
				(width 0.1)
				(type default)
			)
			(layer "F.Fab")
		)
		(fp_line
			(start 0.12065 -0.2794)
			(end 0.12065 -0.3048)
			(stroke
				(width 0.1)
				(type default)
			)
			(layer "F.Fab")
		)
		(fp_line
			(start 0.67945 -0.3048)
			(end 0.67945 0.3048)
			(stroke
				(width 0.1)
				(type default)
			)
			(layer "F.Fab")
		)
		(fp_line
			(start 0.67945 0.3048)
			(end 0.120396 0.3048)
			(stroke
				(width 0.1)
				(type default)
			)
			(layer "F.Fab")
		)
		(pad "1" smd circle
			(at -0.40005 0)
			(size 0 0)
			(layers "F.Cu" "F.Mask" "F.Paste")
			(net "PVDDIO_P1_LSET2")
		)
		(pad "2" smd circle
			(at 0.40005 0)
			(size 0 0)
			(layers "F.Cu" "F.Mask" "F.Paste")
			(net "GND")
		)
	)
	(footprint ""
		(layer "F.Cu")
		(at 8.406384 -380.470156)
		(property "Reference" "PR6600"
			(at 0 0 0)
			(layer "F.SilkS")
			(hide yes)
			(effects
				(font
					(size 1.27 1.27)
				)
			)
		)
		(property "Value" ""
			(at 0 0 0)
			(layer "F.Fab")
			(effects
				(font
					(size 1.27 1.27)
				)
			)
		)
		(duplicate_pad_numbers_are_jumpers no)
		(fp_line
			(start -0.7874 -0.4064)
			(end 0.7874 -0.4064)
			(stroke
				(width 0.1524)
				(type default)
			)
			(layer "F.SilkS")
		)
		(fp_line
			(start -0.7874 0.4064)
			(end -0.7874 -0.4064)
			(stroke
				(width 0.1524)
				(type default)
			)
			(layer "F.SilkS")
		)
		(fp_line
			(start 0.7874 -0.4064)
			(end 0.7874 0.4064)
			(stroke
				(width 0.1524)
				(type default)
			)
			(layer "F.SilkS")
		)
		(fp_line
			(start 0.7874 0.4064)
			(end -0.7874 0.4064)
			(stroke
				(width 0.1524)
				(type default)
			)
			(layer "F.SilkS")
		)
		(fp_line
			(start -0.67945 -0.305054)
			(end -0.12065 -0.305054)
			(stroke
				(width 0.1)
				(type default)
			)
			(layer "F.Fab")
		)
		(fp_line
			(start -0.67945 0.3048)
			(end -0.67945 -0.305054)
			(stroke
				(width 0.1)
				(type default)
			)
			(layer "F.Fab")
		)
		(fp_line
			(start -0.12065 -0.305054)
			(end -0.12065 -0.2794)
			(stroke
				(width 0.1)
				(type default)
			)
			(layer "F.Fab")
		)
		(fp_line
			(start -0.12065 -0.2794)
			(end 0.12065 -0.2794)
			(stroke
				(width 0.1)
				(type default)
			)
			(layer "F.Fab")
		)
		(fp_line
			(start -0.12065 0.2794)
			(end -0.12065 0.3048)
			(stroke
				(width 0.1)
				(type default)
			)
			(layer "F.Fab")
		)
		(fp_line
			(start -0.12065 0.3048)
			(end -0.67945 0.3048)
			(stroke
				(width 0.1)
				(type default)
			)
			(layer "F.Fab")
		)
		(fp_line
			(start 0.120396 0.2794)
			(end -0.12065 0.2794)
			(stroke
				(width 0.1)
				(type default)
			)
			(layer "F.Fab")
		)
		(fp_line
			(start 0.120396 0.3048)
			(end 0.120396 0.2794)
			(stroke
				(width 0.1)
				(type default)
			)
			(layer "F.Fab")
		)
		(fp_line
			(start 0.12065 -0.3048)
			(end 0.67945 -0.3048)
			(stroke
				(width 0.1)
				(type default)
			)
			(layer "F.Fab")
		)
		(fp_line
			(start 0.12065 -0.2794)
			(end 0.12065 -0.3048)
			(stroke
				(width 0.1)
				(type default)
			)
			(layer "F.Fab")
		)
		(fp_line
			(start 0.67945 -0.3048)
			(end 0.67945 0.3048)
			(stroke
				(width 0.1)
				(type default)
			)
			(layer "F.Fab")
		)
		(fp_line
			(start 0.67945 0.3048)
			(end 0.120396 0.3048)
			(stroke
				(width 0.1)
				(type default)
			)
			(layer "F.Fab")
		)
		(pad "1" smd circle
			(at -0.40005 0)
			(size 0 0)
			(layers "F.Cu" "F.Mask" "F.Paste")
			(net "P0V9_RETIMER_CPU1_SENSE_SH_P")
		)
		(pad "2" smd circle
			(at 0.40005 0)
			(size 0 0)
			(layers "F.Cu" "F.Mask" "F.Paste")
			(net "P0V9_CPU1_RT_2D")
		)
	)
)
